(kicad_pcb
	(version 20260206)
	(generator "pcbnew")
	(generator_version "10.0")
	(general
		(thickness 1.6)
		(legacy_teardrops no)
	)
	(paper "A4")
	(title_block
		(title "Wiwynn_Tioga_Pass_MB.brd")
		(comment 1 "Tioga Pass / footprints 191-197 of 4770")
	)
	(layers
		(0 "F.Cu" signal "TOP")
		(4 "In1.Cu" signal "L2GND")
		(6 "In2.Cu" signal "L3")
		(8 "In3.Cu" signal "L4GND")
		(10 "In4.Cu" signal "L5")
		(12 "In5.Cu" signal "L6GND")
		(14 "In6.Cu" signal "L7VCC")
		(16 "In7.Cu" signal "L8VCC")
		(18 "In8.Cu" signal "L9GND")
		(20 "In9.Cu" signal "L10")
		(22 "In10.Cu" signal "L11GND")
		(24 "In11.Cu" signal "L12")
		(26 "In12.Cu" signal "L13GND")
		(2 "B.Cu" signal "BOTTOM")
		(9 "F.Adhes" user "F.Adhesive")
		(11 "B.Adhes" user "B.Adhesive")
		(13 "F.Paste" user "Package Geometry/Pastemask Top")
		(15 "B.Paste" user "Package Geometry/Pastemask Bottom")
		(5 "F.SilkS" user "Ref Des/Silkscreen Top")
		(7 "B.SilkS" user "Ref Des/Silkscreen Bottom")
		(1 "F.Mask" user "Board Geometry/Soldermask Top")
		(3 "B.Mask" user "Board Geometry/Soldermask Bottom")
		(17 "Dwgs.User" user "User.Drawings")
		(19 "Cmts.User" user "User.Comments")
		(21 "Eco1.User" user "User.Eco1")
		(23 "Eco2.User" user "User.Eco2")
		(25 "Edge.Cuts" user "Board Geometry/Outline")
		(27 "Margin" user)
		(31 "F.CrtYd" user "Package Geometry/Place Bound Top")
		(29 "B.CrtYd" user "Package Geometry/Place Bound Bottom")
		(35 "F.Fab" user "Ref Des/Assembly Top")
		(33 "B.Fab" user "Ref Des/Assembly Bottom")
	)
	(footprint ""
		(layer "F.Cu")
		(at 9.779 -155.702)
		(property "Reference" ""
			(at 0 0 0)
			(layer "F.SilkS")
			(hide yes)
			(effects
				(font
					(size 1.27 1.27)
				)
			)
		)
		(property "Value" ""
			(at 0 0 0)
			(layer "F.Fab")
			(effects
				(font
					(size 1.27 1.27)
				)
			)
		)
		(duplicate_pad_numbers_are_jumpers no)
		(fp_poly
			(pts
				(arc
					(start 2.032 0)
					(mid -2.032 0)
					(end 2.032 0)
				)
			)
			(stroke
				(width 0)
				(type default)
			)
			(fill no)
			(layer "F.CrtYd")
		)
		(pad "1" smd circle
			(at 0 0)
			(size 1.016 1.016)
			(layers "F.Cu" "F.Mask" "F.Paste")
			(net "Net_384")
		)
		(zone
			(layer "F.Cu")
			(hatch none 0.5)
			(connect_pads
				(clearance 0)
			)
			(min_thickness 0.25)
			(keepout
				(tracks not_allowed)
				(vias allowed)
				(pads allowed)
				(copperpour not_allowed)
				(footprints allowed)
			)
			(placement
				(enabled no)
				(sheetname "")
			)
			(fill
				(thermal_gap 0.5)
				(thermal_bridge_width 0.5)
				(island_removal_mode 0)
			)
			(polygon
				(pts
					(arc
						(start 11.303 -155.702)
						(mid 8.255 -155.702)
						(end 11.303 -155.702)
					)
				)
			)
		)
		(zone
			(layers "F.Cu" "B.Cu" "In1.Cu" "In2.Cu" "In3.Cu" "In4.Cu" "In5.Cu" "In6.Cu"
				"In7.Cu" "In8.Cu" "In9.Cu" "In10.Cu" "In11.Cu" "In12.Cu"
			)
			(hatch none 0.5)
			(connect_pads
				(clearance 0)
			)
			(min_thickness 0.25)
			(keepout
				(tracks allowed)
				(vias not_allowed)
				(pads allowed)
				(copperpour not_allowed)
				(footprints allowed)
			)
			(placement
				(enabled no)
				(sheetname "")
			)
			(fill
				(thermal_gap 0.5)
				(thermal_bridge_width 0.5)
				(island_removal_mode 0)
			)
			(polygon
				(pts
					(arc
						(start 11.303 -155.702)
						(mid 8.255 -155.702)
						(end 11.303 -155.702)
					)
				)
			)
		)
	)
	(footprint ""
		(layer "F.Cu")
		(at 460.121 -1.524 -90)
		(property "Reference" "R8B26"
			(at -0.8382 -0.67818 270)
			(unlocked yes)
			(layer "F.SilkS")
			(effects
				(font
					(size 0.4064 0.254)
					(thickness 0.1524)
				)
				(justify left)
			)
		)
		(property "Value" ""
			(at 0 0 270)
			(layer "F.Fab")
			(effects
				(font
					(size 1.27 1.27)
				)
			)
		)
		(duplicate_pad_numbers_are_jumpers no)
		(fp_poly
			(pts
				(xy -0.2794 -0.1016) (xy 0.2794 -0.1016) (xy 0.2794 0.9906) (xy -0.2794 0.9906)
			)
			(stroke
				(width 0)
				(type default)
			)
			(fill no)
			(layer "F.CrtYd")
		)
		(fp_line
			(start -0.2794 0.9906)
			(end 0.2794 0.9906)
			(stroke
				(width 0.1)
				(type default)
			)
			(layer "F.Fab")
		)
		(fp_line
			(start 0.2794 0.9906)
			(end 0.2794 -0.1016)
			(stroke
				(width 0.1)
				(type default)
			)
			(layer "F.Fab")
		)
		(fp_line
			(start -0.2794 -0.1016)
			(end -0.2794 0.9906)
			(stroke
				(width 0.1)
				(type default)
			)
			(layer "F.Fab")
		)
		(fp_line
			(start 0.2794 -0.1016)
			(end -0.2794 -0.1016)
			(stroke
				(width 0.1)
				(type default)
			)
			(layer "F.Fab")
		)
		(pad "1" smd rect
			(at 0 0 270)
			(size 0.508 0.508)
			(layers "F.Cu" "F.Mask" "F.Paste")
			(net "P3V3_STBY")
		)
		(pad "2" smd rect
			(at 0 0.889 270)
			(size 0.508 0.508)
			(layers "F.Cu" "F.Mask" "F.Paste")
			(net "SMB_HOST_STBY_LVC3_SCL_R5")
		)
		(zone
			(layer "F.Cu")
			(hatch none 0.5)
			(connect_pads
				(clearance 0)
			)
			(min_thickness 0.25)
			(keepout
				(tracks not_allowed)
				(vias allowed)
				(pads allowed)
				(copperpour not_allowed)
				(footprints allowed)
			)
			(placement
				(enabled no)
				(sheetname "")
			)
			(fill
				(thermal_gap 0.5)
				(thermal_bridge_width 0.5)
				(island_removal_mode 0)
			)
			(polygon
				(pts
					(xy 459.486 -1.778) (xy 459.486 -1.27) (xy 459.867 -1.27) (xy 459.867 -1.778)
				)
			)
		)
		(zone
			(layer "F.Cu")
			(hatch none 0.5)
			(connect_pads
				(clearance 0)
			)
			(min_thickness 0.25)
			(keepout
				(tracks allowed)
				(vias not_allowed)
				(pads allowed)
				(copperpour not_allowed)
				(footprints allowed)
			)
			(placement
				(enabled no)
				(sheetname "")
			)
			(fill
				(thermal_gap 0.5)
				(thermal_bridge_width 0.5)
				(island_removal_mode 0)
			)
			(polygon
				(pts
					(xy 459.867 -1.778) (xy 459.867 -1.27) (xy 459.486 -1.27) (xy 459.486 -1.778)
				)
			)
		)
	)
	(footprint ""
		(layer "F.Cu")
		(at 500.579898 -42.61993 90)
		(property "Reference" "J25W1"
			(at 0 0 90)
			(layer "F.SilkS")
			(hide yes)
			(effects
				(font
					(size 1.27 1.27)
				)
			)
		)
		(property "Value" "*"
			(at 4.3434 -6.4643 90)
			(unlocked yes)
			(layer "F.Fab")
			(hide yes)
			(effects
				(font
					(size 1.27 1.016)
					(thickness 0.1524)
				)
			)
		)
		(property "Device Type" "SMC-CON13-GP_CONN-GC2-SMC-CON1A"
			(at 4.3434 -7.9883 90)
			(unlocked yes)
			(layer "F.Fab")
			(hide yes)
			(effects
				(font
					(size 1.27 1.016)
					(thickness 0.1524)
				)
			)
		)
		(duplicate_pad_numbers_are_jumpers no)
		(fp_line
			(start -6.6548 -5.0038)
			(end -5.7023 -5.0038)
			(stroke
				(width 0.3302)
				(type default)
			)
			(layer "F.SilkS")
		)
		(fp_line
			(start 6.5659 -4.9149)
			(end 6.5659 -3.7973)
			(stroke
				(width 0.1524)
				(type default)
			)
			(layer "F.SilkS")
		)
		(fp_line
			(start -6.5659 -4.9149)
			(end 6.5659 -4.9149)
			(stroke
				(width 0.1524)
				(type default)
			)
			(layer "F.SilkS")
		)
		(fp_line
			(start -6.6548 -3.8989)
			(end -6.6548 -5.0038)
			(stroke
				(width 0.3302)
				(type default)
			)
			(layer "F.SilkS")
		)
		(fp_line
			(start 7.9629 -3.7973)
			(end 7.9629 1.1557)
			(stroke
				(width 0.1524)
				(type default)
			)
			(layer "F.SilkS")
		)
		(fp_line
			(start 6.5659 -3.7973)
			(end 7.9629 -3.7973)
			(stroke
				(width 0.1524)
				(type default)
			)
			(layer "F.SilkS")
		)
		(fp_line
			(start -6.5659 -3.7973)
			(end -6.5659 -4.9149)
			(stroke
				(width 0.1524)
				(type default)
			)
			(layer "F.SilkS")
		)
		(fp_line
			(start -7.9629 -3.7973)
			(end -6.5659 -3.7973)
			(stroke
				(width 0.1524)
				(type default)
			)
			(layer "F.SilkS")
		)
		(fp_line
			(start 7.9629 1.1557)
			(end -7.9629 1.1557)
			(stroke
				(width 0.1524)
				(type default)
			)
			(layer "F.SilkS")
		)
		(fp_line
			(start -7.9629 1.1557)
			(end -7.9629 -3.7973)
			(stroke
				(width 0.1524)
				(type default)
			)
			(layer "F.SilkS")
		)
		(fp_poly
			(pts
				(xy -6.052312 -4.930902) (xy -5.428488 -5.554726) (xy -6.676136 -5.554726)
			)
			(stroke
				(width 0)
				(type default)
			)
			(fill yes)
			(layer "F.SilkS")
		)
		(fp_poly
			(pts
				(xy -6.69036 -2.897124) (xy -6.69036 1.1684) (xy 6.69036 1.1684) (xy 6.69036 -2.897124)
			)
			(stroke
				(width 0)
				(type default)
			)
			(fill yes)
			(layer "F.SilkS")
		)
		(fp_poly
			(pts
				(xy -7.5057 0.6985) (xy -7.5057 -3.5433) (xy -6.096 -3.5433) (xy -6.096 -4.2545) (xy 6.096 -4.2545)
				(xy 6.096 -3.5433) (xy 7.5057 -3.5433) (xy 7.5057 0.6985)
			)
			(stroke
				(width 0)
				(type default)
			)
			(fill no)
			(layer "F.CrtYd")
		)
		(fp_poly
			(pts
				(xy -8.2169 1.4097) (xy -8.2169 -4.0513) (xy -6.8199 -4.0513) (xy -6.8199 -5.1689) (xy 6.8199 -5.1689)
				(xy 6.8199 -4.0513) (xy 8.2169 -4.0513) (xy 8.2169 -0.00635) (xy 7.5057 -0.00635) (xy 7.5057 -3.5433)
				(xy 6.096 -3.5433) (xy 6.096 -4.2545) (xy -6.096 -4.2545) (xy -6.096 -3.5433) (xy -7.5057 -3.5433)
				(xy -7.5057 0.6985) (xy 7.5057 0.6985) (xy 7.5057 0.00635) (xy 8.2169 0.00635) (xy 8.2169 1.4097)
			)
			(stroke
				(width 0)
				(type default)
			)
			(fill no)
			(layer "F.CrtYd")
		)
		(fp_poly
			(pts
				(xy -8.2169 1.4097) (xy -8.2169 -4.0513) (xy -6.8199 -4.0513) (xy -6.8199 -5.1689) (xy 6.8199 -5.1689)
				(xy 6.8199 -4.0513) (xy 8.2169 -4.0513) (xy 8.2169 1.4097)
			)
			(stroke
				(width 0)
				(type default)
			)
			(fill no)
			(layer "F.Fab")
		)
		(pad "1" smd rect
			(at -5.999988 -3.875024 90)
			(size 0.6096 1.5494)
			(layers "F.Cu" "F.Mask" "F.Paste")
			(net "V_IO_R_J")
		)
		(pad "2" smd rect
			(at -4.99999 -3.875024 90)
			(size 0.6096 1.5494)
			(layers "F.Cu" "F.Mask" "F.Paste")
			(net "GND")
		)
		(pad "3" smd rect
			(at -3.999992 -3.875024 90)
			(size 0.6096 1.5494)
			(layers "F.Cu" "F.Mask" "F.Paste")
			(net "V_IO_G_J")
		)
		(pad "4" smd rect
			(at -2.999994 -3.875024 90)
			(size 0.6096 1.5494)
			(layers "F.Cu" "F.Mask" "F.Paste")
			(net "GND")
		)
		(pad "5" smd rect
			(at -1.999996 -3.875024 90)
			(size 0.6096 1.5494)
			(layers "F.Cu" "F.Mask" "F.Paste")
			(net "V_IO_B_J")
		)
		(pad "6" smd rect
			(at -0.999998 -3.875024 90)
			(size 0.6096 1.5494)
			(layers "F.Cu" "F.Mask" "F.Paste")
			(net "GND")
		)
		(pad "7" smd rect
			(at 0 -3.875024 90)
			(size 0.6096 1.5494)
			(layers "F.Cu" "F.Mask" "F.Paste")
			(net "V_IO_VSYNC_J")
		)
		(pad "8" smd rect
			(at 0.999998 -3.875024 90)
			(size 0.6096 1.5494)
			(layers "F.Cu" "F.Mask" "F.Paste")
			(net "GND")
		)
		(pad "9" smd rect
			(at 1.999996 -3.875024 90)
			(size 0.6096 1.5494)
			(layers "F.Cu" "F.Mask" "F.Paste")
			(net "V_IO_HSYNC_J")
		)
		(pad "10" smd rect
			(at 2.999994 -3.875024 90)
			(size 0.6096 1.5494)
			(layers "F.Cu" "F.Mask" "F.Paste")
			(net "GND")
		)
		(pad "11" smd rect
			(at 3.999992 -3.875024 90)
			(size 0.6096 1.5494)
			(layers "F.Cu" "F.Mask" "F.Paste")
			(net "V_IBMC_5V_DDC_SDA_J")
		)
		(pad "12" smd rect
			(at 4.99999 -3.875024 90)
			(size 0.6096 1.5494)
			(layers "F.Cu" "F.Mask" "F.Paste")
			(net "V_IBMC_5V_DDC_SCL_J")
		)
		(pad "13" smd rect
			(at 5.999988 -3.875024 90)
			(size 0.6096 1.5494)
			(layers "F.Cu" "F.Mask" "F.Paste")
			(net "P5V_VGA")
		)
		(pad "PTH1" smd rect
			(at -7.29996 0 90)
			(size 0.8128 1.8034)
			(layers "F.Cu" "F.Mask" "F.Paste")
			(net "GND")
		)
		(pad "PTH2" smd rect
			(at 7.29996 0 90)
			(size 0.8128 1.8034)
			(layers "F.Cu" "F.Mask" "F.Paste")
			(net "GND")
		)
	)
	(footprint ""
		(layer "F.Cu")
		(at 39.6748 -50.5714 90)
		(property "Reference" "R1E6"
			(at 0 0 90)
			(layer "F.SilkS")
			(hide yes)
			(effects
				(font
					(size 1.27 1.27)
				)
			)
		)
		(property "Value" ""
			(at 0 0 90)
			(layer "F.Fab")
			(effects
				(font
					(size 1.27 1.27)
				)
			)
		)
		(duplicate_pad_numbers_are_jumpers no)
		(fp_poly
			(pts
				(xy -0.2794 -0.1016) (xy 0.2794 -0.1016) (xy 0.2794 0.9906) (xy -0.2794 0.9906)
			)
			(stroke
				(width 0)
				(type default)
			)
			(fill no)
			(layer "F.CrtYd")
		)
		(fp_line
			(start 0.2794 -0.1016)
			(end -0.2794 -0.1016)
			(stroke
				(width 0.1)
				(type default)
			)
			(layer "F.Fab")
		)
		(fp_line
			(start -0.2794 -0.1016)
			(end -0.2794 0.9906)
			(stroke
				(width 0.1)
				(type default)
			)
			(layer "F.Fab")
		)
		(fp_line
			(start 0.2794 0.9906)
			(end 0.2794 -0.1016)
			(stroke
				(width 0.1)
				(type default)
			)
			(layer "F.Fab")
		)
		(fp_line
			(start -0.2794 0.9906)
			(end 0.2794 0.9906)
			(stroke
				(width 0.1)
				(type default)
			)
			(layer "F.Fab")
		)
		(pad "1" smd rect
			(at 0 0 90)
			(size 0.508 0.508)
			(layers "F.Cu" "F.Mask" "F.Paste")
			(net "VSENSE_PVCCIN_CPU1_P")
		)
		(pad "2" smd rect
			(at 0 0.889 90)
			(size 0.508 0.508)
			(layers "F.Cu" "F.Mask" "F.Paste")
			(net "VSENSE_PVCCIN_CPU1_SKT_VSEN")
		)
		(zone
			(layer "F.Cu")
			(hatch none 0.5)
			(connect_pads
				(clearance 0)
			)
			(min_thickness 0.25)
			(keepout
				(tracks allowed)
				(vias not_allowed)
				(pads allowed)
				(copperpour not_allowed)
				(footprints allowed)
			)
			(placement
				(enabled no)
				(sheetname "")
			)
			(fill
				(thermal_gap 0.5)
				(thermal_bridge_width 0.5)
				(island_removal_mode 0)
			)
			(polygon
				(pts
					(xy 39.9288 -50.3174) (xy 39.9288 -50.8254) (xy 40.3098 -50.8254) (xy 40.3098 -50.3174)
				)
			)
		)
		(zone
			(layer "F.Cu")
			(hatch none 0.5)
			(connect_pads
				(clearance 0)
			)
			(min_thickness 0.25)
			(keepout
				(tracks not_allowed)
				(vias allowed)
				(pads allowed)
				(copperpour not_allowed)
				(footprints allowed)
			)
			(placement
				(enabled no)
				(sheetname "")
			)
			(fill
				(thermal_gap 0.5)
				(thermal_bridge_width 0.5)
				(island_removal_mode 0)
			)
			(polygon
				(pts
					(xy 40.3098 -50.3174) (xy 40.3098 -50.8254) (xy 39.9288 -50.8254) (xy 39.9288 -50.3174)
				)
			)
		)
	)
	(footprint ""
		(layer "F.Cu")
		(at 335.788 -24.13 90)
		(property "Reference" "R7F13"
			(at 0 0 90)
			(layer "F.SilkS")
			(hide yes)
			(effects
				(font
					(size 1.27 1.27)
				)
			)
		)
		(property "Value" ""
			(at 0 0 90)
			(layer "F.Fab")
			(effects
				(font
					(size 1.27 1.27)
				)
			)
		)
		(duplicate_pad_numbers_are_jumpers no)
		(fp_rect
			(start -0.2794 -0.1016)
			(end 0.2794 0.9906)
			(stroke
				(width 0)
				(type default)
			)
			(fill no)
			(layer "F.CrtYd")
		)
		(fp_line
			(start 0.2794 -0.1016)
			(end -0.2794 -0.1016)
			(stroke
				(width 0.1)
				(type default)
			)
			(layer "F.Fab")
		)
		(fp_line
			(start -0.2794 -0.1016)
			(end -0.2794 0.9906)
			(stroke
				(width 0.1)
				(type default)
			)
			(layer "F.Fab")
		)
		(fp_line
			(start 0.2794 0.9906)
			(end 0.2794 -0.1016)
			(stroke
				(width 0.1)
				(type default)
			)
			(layer "F.Fab")
		)
		(fp_line
			(start -0.2794 0.9906)
			(end 0.2794 0.9906)
			(stroke
				(width 0.1)
				(type default)
			)
			(layer "F.Fab")
		)
		(pad "1" smd rect
			(at 0 0 90)
			(size 0.508 0.508)
			(layers "F.Cu" "F.Mask" "F.Paste")
			(net "VSENSE_PVPP_ABC")
		)
		(pad "2" smd rect
			(at 0 0.889 90)
			(size 0.508 0.508)
			(layers "F.Cu" "F.Mask" "F.Paste")
			(net "VR_FB_PVPP_ABC")
		)
		(zone
			(layer "F.Cu")
			(hatch none 0.5)
			(connect_pads
				(clearance 0)
			)
			(min_thickness 0.25)
			(keepout
				(tracks allowed)
				(vias not_allowed)
				(pads allowed)
				(copperpour not_allowed)
				(footprints allowed)
			)
			(placement
				(enabled no)
				(sheetname "")
			)
			(fill
				(thermal_gap 0.5)
				(thermal_bridge_width 0.5)
				(island_removal_mode 0)
			)
			(polygon
				(pts
					(xy 336.042 -23.876) (xy 336.423 -23.876) (xy 336.423 -24.384) (xy 336.042 -24.384)
				)
			)
		)
		(zone
			(layer "F.Cu")
			(hatch none 0.5)
			(connect_pads
				(clearance 0)
			)
			(min_thickness 0.25)
			(keepout
				(tracks not_allowed)
				(vias allowed)
				(pads allowed)
				(copperpour not_allowed)
				(footprints allowed)
			)
			(placement
				(enabled no)
				(sheetname "")
			)
			(fill
				(thermal_gap 0.5)
				(thermal_bridge_width 0.5)
				(island_removal_mode 0)
			)
			(polygon
				(pts
					(xy 336.042 -23.876) (xy 336.423 -23.876) (xy 336.423 -24.384) (xy 336.042 -24.384)
				)
			)
		)
	)
	(footprint ""
		(layer "F.Cu")
		(at 481.8126 -21.1582)
		(property "Reference" "C22W12"
			(at 0 0 0)
			(layer "F.SilkS")
			(hide yes)
			(effects
				(font
					(size 1.27 1.27)
				)
			)
		)
		(property "Value" "*"
			(at -0.0762 -6.2357 0)
			(unlocked yes)
			(layer "F.Fab")
			(hide yes)
			(effects
				(font
					(size 1.27 1.016)
					(thickness 0.1524)
				)
			)
		)
		(property "Device Type" "SC22U16V5MX-4-GP_SMD-BCG5-SC22A"
			(at -0.0762 -8.2677 0)
			(unlocked yes)
			(layer "F.Fab")
			(hide yes)
			(effects
				(font
					(size 1.27 1.016)
					(thickness 0.1524)
				)
			)
		)
		(duplicate_pad_numbers_are_jumpers no)
		(fp_line
			(start 0.635 0)
			(end -0.635 0)
			(stroke
				(width 0.508)
				(type default)
			)
			(layer "F.SilkS")
		)
		(fp_rect
			(start -0.9652 1.778)
			(end 0.9652 -1.778)
			(stroke
				(width 0)
				(type default)
			)
			(fill no)
			(layer "F.CrtYd")
		)
		(fp_poly
			(pts
				(xy -0.9652 -1.778) (xy 0.9652 -1.778) (xy 0.9652 1.778) (xy -0.9652 1.778)
			)
			(stroke
				(width 0)
				(type default)
			)
			(fill no)
			(layer "F.Fab")
		)
		(pad "1" smd rect
			(at 0 -0.9652)
			(size 1.397 1.143)
			(layers "F.Cu" "F.Mask" "F.Paste")
			(net "VR_FET_SW_P12V_STBY_P3V3_STBY")
		)
		(pad "2" smd rect
			(at 0 0.9652)
			(size 1.397 1.143)
			(layers "F.Cu" "F.Mask" "F.Paste")
			(net "GND")
		)
	)
	(footprint ""
		(layer "F.Cu")
		(at 402.336 -152.527 180)
		(property "Reference" "C8A6"
			(at 0 0 180)
			(layer "F.SilkS")
			(hide yes)
			(effects
				(font
					(size 1.27 1.27)
				)
			)
		)
		(property "Value" ""
			(at 0 0 180)
			(layer "F.Fab")
			(effects
				(font
					(size 1.27 1.27)
				)
			)
		)
		(duplicate_pad_numbers_are_jumpers no)
		(fp_poly
			(pts
				(xy -0.4953 -0.2032) (xy 0.4953 -0.2032) (xy 0.4953 1.6002) (xy -0.4953 1.6002)
			)
			(stroke
				(width 0)
				(type default)
			)
			(fill no)
			(layer "F.CrtYd")
		)
		(fp_line
			(start 0.4953 1.6002)
			(end -0.4953 1.6002)
			(stroke
				(width 0.1)
				(type default)
			)
			(layer "F.Fab")
		)
		(fp_line
			(start 0.4953 -0.2032)
			(end 0.4953 1.6002)
			(stroke
				(width 0.1)
				(type default)
			)
			(layer "F.Fab")
		)
		(fp_line
			(start -0.4953 1.6002)
			(end -0.4953 -0.2032)
			(stroke
				(width 0.1)
				(type default)
			)
			(layer "F.Fab")
		)
		(fp_line
			(start -0.4953 -0.2032)
			(end 0.4953 -0.2032)
			(stroke
				(width 0.1)
				(type default)
			)
			(layer "F.Fab")
		)
		(pad "1" smd rect
			(at 0 0 180)
			(size 0.762 0.889)
			(layers "F.Cu" "F.Mask" "F.Paste")
			(net "P3V3_STBY")
		)
		(pad "2" smd rect
			(at 0 1.397 180)
			(size 0.762 0.889)
			(layers "F.Cu" "F.Mask" "F.Paste")
			(net "GND")
		)
		(zone
			(layer "F.Cu")
			(hatch none 0.5)
			(connect_pads
				(clearance 0)
			)
			(min_thickness 0.25)
			(keepout
				(tracks not_allowed)
				(vias allowed)
				(pads allowed)
				(copperpour not_allowed)
				(footprints allowed)
			)
			(placement
				(enabled no)
				(sheetname "")
			)
			(fill
				(thermal_gap 0.5)
				(thermal_bridge_width 0.5)
				(island_removal_mode 0)
			)
			(polygon
				(pts
					(xy 402.717 -152.9715) (xy 401.955 -152.9715) (xy 401.955 -153.4795) (xy 402.717 -153.4795)
				)
			)
		)
	)
)
